(kicad_pcb
	(version 20260206)
	(generator "pcbnew")
	(generator_version "10.0")
	(general
		(thickness 1.6)
		(legacy_teardrops no)
	)
	(paper "A4")
	(title_block
		(title "v1-chassis-manager — T6M_CM_d_v01_1031_1645.brd")
		(comment 1 "Open CloudServer (Microsoft) / footprints 1365-1371 of 2512")
	)
	(layers
		(0 "F.Cu" signal "TOP")
		(4 "In1.Cu" signal "GND1")
		(6 "In2.Cu" signal "IN1")
		(8 "In3.Cu" signal "VCC1")
		(10 "In4.Cu" signal "VCC2")
		(12 "In5.Cu" signal "GND2")
		(14 "In6.Cu" signal "IN2")
		(16 "In7.Cu" signal "IN3")
		(18 "In8.Cu" signal "GND3")
		(2 "B.Cu" signal "BOTTOM")
		(9 "F.Adhes" user "F.Adhesive")
		(11 "B.Adhes" user "B.Adhesive")
		(13 "F.Paste" user "Package Geometry/Pastemask Top")
		(15 "B.Paste" user "Package Geometry/Pastemask Bottom")
		(5 "F.SilkS" user "Ref Des/Silkscreen Top")
		(7 "B.SilkS" user "Ref Des/Silkscreen Bottom")
		(1 "F.Mask" user "Board Geometry/Soldermask Top")
		(3 "B.Mask" user "Board Geometry/Soldermask Bottom")
		(17 "Dwgs.User" user "User.Drawings")
		(19 "Cmts.User" user "User.Comments")
		(21 "Eco1.User" user "User.Eco1")
		(23 "Eco2.User" user "User.Eco2")
		(25 "Edge.Cuts" user "Board Geometry/Outline")
		(27 "Margin" user)
		(31 "F.CrtYd" user "Package Geometry/Place Bound Top")
		(29 "B.CrtYd" user "Package Geometry/Place Bound Bottom")
		(35 "F.Fab" user "Ref Des/Assembly Top")
		(33 "B.Fab" user "Ref Des/Assembly Bottom")
	)
	(footprint ""
		(layer "F.Cu")
		(at 113.368836 -138.0109 180)
		(property "Reference" "PJ15"
			(at -3.553968 3.597656 90)
			(unlocked yes)
			(layer "F.SilkS")
			(effects
				(font
					(size 0.635 0.4064)
					(thickness 0.1524)
				)
				(justify left)
			)
		)
		(property "Value" ""
			(at 0 0 180)
			(layer "F.Fab")
			(effects
				(font
					(size 1.27 1.27)
				)
			)
		)
		(duplicate_pad_numbers_are_jumpers no)
		(fp_poly
			(pts
				(xy 0.2794 0.907796) (xy 0.254 0.907796) (xy 0.254 1.0414) (xy -0.254 1.0414) (xy -0.254 1.034796)
				(xy -0.254 0.933196) (xy -0.2794 0.933196) (xy -0.2794 -0.133604) (xy -0.254 -0.133604) (xy -0.254 -0.235204)
				(xy 0.254 -0.235204) (xy 0.254 -0.133604) (xy 0.2794 -0.133604)
			)
			(stroke
				(width 0)
				(type default)
			)
			(fill no)
			(layer "F.CrtYd")
		)
		(pad "1" smd custom
			(at 0 -0.000254 180)
			(size 0.127 0.127)
			(layers "F.Cu" "F.Mask" "F.Paste")
			(net "VR_PVCCP_NODE1_RGND")
			(options
				(clearance outline)
				(anchor circle)
			)
			(primitives
				(gr_poly
					(pts
						(xy -0.127 0.508) (xy -0.127 -0.0508) (xy -0.254 -0.0508) (xy -0.254 -0.508) (xy 0.254 -0.508)
						(xy 0.254 -0.0508) (xy 0.127 -0.0508) (xy 0.127 0.508)
					)
					(width 0)
					(fill yes)
				)
			)
		)
		(pad "2" smd rect
			(at 0 0.799846 270)
			(size 0.4572 0.508)
			(layers "F.Cu" "F.Mask" "F.Paste")
			(net "VSENSE_VSS_CPU_NODE1")
		)
		(zone
			(layer "F.Cu")
			(hatch none 0.5)
			(connect_pads
				(clearance 0)
			)
			(min_thickness 0.25)
			(keepout
				(tracks allowed)
				(vias not_allowed)
				(pads allowed)
				(copperpour not_allowed)
				(footprints allowed)
			)
			(placement
				(enabled no)
				(sheetname "")
			)
			(fill
				(thermal_gap 0.5)
				(thermal_bridge_width 0.5)
				(island_removal_mode 0)
			)
			(polygon
				(pts
					(xy 113.673636 -139.096496) (xy 113.064036 -139.096496) (xy 113.064036 -137.724896) (xy 113.673636 -137.724896)
				)
			)
		)
	)
	(footprint ""
		(layer "F.Cu")
		(at 66.356992 -7.424166)
		(property "Reference" "PR21"
			(at -1.31572 -4.28625 0)
			(unlocked yes)
			(layer "F.SilkS")
			(effects
				(font
					(size 0.7874 0.5842)
					(thickness 0.1524)
				)
				(justify left)
			)
		)
		(property "Value" ""
			(at 0 0 0)
			(layer "F.Fab")
			(effects
				(font
					(size 1.27 1.27)
				)
			)
		)
		(duplicate_pad_numbers_are_jumpers no)
		(fp_line
			(start -0.7874 -0.4064)
			(end 0.7874 -0.4064)
			(stroke
				(width 0.1524)
				(type default)
			)
			(layer "F.SilkS")
		)
		(fp_line
			(start -0.7874 0.4064)
			(end -0.7874 -0.4064)
			(stroke
				(width 0.1524)
				(type default)
			)
			(layer "F.SilkS")
		)
		(fp_line
			(start 0.7874 -0.4064)
			(end 0.7874 0.4064)
			(stroke
				(width 0.1524)
				(type default)
			)
			(layer "F.SilkS")
		)
		(fp_line
			(start 0.7874 0.4064)
			(end -0.7874 0.4064)
			(stroke
				(width 0.1524)
				(type default)
			)
			(layer "F.SilkS")
		)
		(fp_poly
			(pts
				(xy -0.508 0.2794) (xy -0.508 0.2286) (xy -0.635 0.2286) (xy -0.635 -0.254) (xy -0.5334 -0.254)
				(xy -0.5334 -0.2794) (xy 0.5334 -0.2794) (xy 0.5334 -0.254) (xy 0.635 -0.254) (xy 0.635 0.254) (xy 0.5334 0.254)
				(xy 0.5334 0.2794)
			)
			(stroke
				(width 0)
				(type default)
			)
			(fill no)
			(layer "F.CrtYd")
		)
		(pad "1" smd rect
			(at 0.40005 0)
			(size 0.4572 0.508)
			(layers "F.Cu" "F.Mask" "F.Paste")
			(net "P3V3_NODE1_FB")
		)
		(pad "2" smd rect
			(at -0.40005 0)
			(size 0.4572 0.508)
			(layers "F.Cu" "F.Mask" "F.Paste")
			(net "GND")
		)
	)
	(footprint ""
		(layer "F.Cu")
		(at 44.207176 -178.301904 180)
		(property "Reference" "C772"
			(at 0.98552 -132.632196 0)
			(unlocked yes)
			(layer "F.SilkS")
			(effects
				(font
					(size 0.7874 0.5842)
					(thickness 0.1524)
				)
				(justify left)
			)
		)
		(property "Value" ""
			(at 0 0 180)
			(layer "F.Fab")
			(effects
				(font
					(size 1.27 1.27)
				)
			)
		)
		(duplicate_pad_numbers_are_jumpers no)
		(fp_line
			(start 0.7874 0.4064)
			(end -0.7874 0.4064)
			(stroke
				(width 0.1524)
				(type default)
			)
			(layer "F.SilkS")
		)
		(fp_line
			(start 0.7874 -0.4064)
			(end 0.7874 0.4064)
			(stroke
				(width 0.1524)
				(type default)
			)
			(layer "F.SilkS")
		)
		(fp_line
			(start 0 0.381)
			(end 0 -0.381)
			(stroke
				(width 0.1524)
				(type default)
			)
			(layer "F.SilkS")
		)
		(fp_line
			(start -0.7874 0.4064)
			(end -0.7874 -0.4064)
			(stroke
				(width 0.1524)
				(type default)
			)
			(layer "F.SilkS")
		)
		(fp_line
			(start -0.7874 -0.4064)
			(end 0.7874 -0.4064)
			(stroke
				(width 0.1524)
				(type default)
			)
			(layer "F.SilkS")
		)
		(fp_poly
			(pts
				(xy -0.5334 0.254) (xy -0.635 0.254) (xy -0.635 0.2286) (xy -0.635 -0.254) (xy -0.5334 -0.254) (xy -0.5334 -0.2794)
				(xy 0.5334 -0.2794) (xy 0.5334 -0.254) (xy 0.635 -0.254) (xy 0.635 0.254) (xy 0.5334 0.254) (xy 0.5334 0.2794)
				(xy -0.508 0.2794) (xy -0.5334 0.2794)
			)
			(stroke
				(width 0)
				(type default)
			)
			(fill no)
			(layer "F.CrtYd")
		)
		(pad "1" smd rect
			(at 0.40005 0 180)
			(size 0.4572 0.508)
			(layers "F.Cu" "F.Mask" "F.Paste")
			(net "P12V_AUX")
		)
		(pad "2" smd rect
			(at -0.40005 0 180)
			(size 0.4572 0.508)
			(layers "F.Cu" "F.Mask" "F.Paste")
			(net "GND")
		)
	)
	(footprint ""
		(layer "F.Cu")
		(at 134.807452 -154.81935 -90)
		(property "Reference" "R234"
			(at 110.801912 60.44946 90)
			(unlocked yes)
			(layer "F.SilkS")
			(effects
				(font
					(size 0.7874 0.5842)
					(thickness 0.1524)
				)
				(justify left)
			)
		)
		(property "Value" ""
			(at 0 0 270)
			(layer "F.Fab")
			(effects
				(font
					(size 1.27 1.27)
				)
			)
		)
		(duplicate_pad_numbers_are_jumpers no)
		(fp_line
			(start -0.7874 0.4064)
			(end -0.7874 -0.4064)
			(stroke
				(width 0.1524)
				(type default)
			)
			(layer "F.SilkS")
		)
		(fp_line
			(start 0.7874 0.4064)
			(end -0.7874 0.4064)
			(stroke
				(width 0.1524)
				(type default)
			)
			(layer "F.SilkS")
		)
		(fp_line
			(start -0.7874 -0.4064)
			(end 0.7874 -0.4064)
			(stroke
				(width 0.1524)
				(type default)
			)
			(layer "F.SilkS")
		)
		(fp_line
			(start 0.7874 -0.4064)
			(end 0.7874 0.4064)
			(stroke
				(width 0.1524)
				(type default)
			)
			(layer "F.SilkS")
		)
		(fp_poly
			(pts
				(xy -0.508 0.2794) (xy -0.508 0.2286) (xy -0.635 0.2286) (xy -0.635 -0.254) (xy -0.5334 -0.254)
				(xy -0.5334 -0.2794) (xy 0.5334 -0.2794) (xy 0.5334 -0.254) (xy 0.635 -0.254) (xy 0.635 0.254) (xy 0.5334 0.254)
				(xy 0.5334 0.2794)
			)
			(stroke
				(width 0)
				(type default)
			)
			(fill no)
			(layer "F.CrtYd")
		)
		(pad "1" smd rect
			(at 0.40005 0 270)
			(size 0.4572 0.508)
			(layers "F.Cu" "F.Mask" "F.Paste")
			(net "PCIE_SW_P0_ERR_R")
		)
		(pad "2" smd rect
			(at -0.40005 0 270)
			(size 0.4572 0.508)
			(layers "F.Cu" "F.Mask" "F.Paste")
			(net "PCIE_SW_P0_ERR")
		)
	)
	(footprint ""
		(layer "F.Cu")
		(at 138.991086 -156.743908 180)
		(property "Reference" "R1226"
			(at 63.166244 -109.010196 0)
			(unlocked yes)
			(layer "F.SilkS")
			(effects
				(font
					(size 0.7874 0.5842)
					(thickness 0.1524)
				)
				(justify left)
			)
		)
		(property "Value" ""
			(at 0 0 180)
			(layer "F.Fab")
			(effects
				(font
					(size 1.27 1.27)
				)
			)
		)
		(duplicate_pad_numbers_are_jumpers no)
		(fp_line
			(start 0.7874 0.4064)
			(end -0.7874 0.4064)
			(stroke
				(width 0.1524)
				(type default)
			)
			(layer "F.SilkS")
		)
		(fp_line
			(start 0.7874 -0.4064)
			(end 0.7874 0.4064)
			(stroke
				(width 0.1524)
				(type default)
			)
			(layer "F.SilkS")
		)
		(fp_line
			(start -0.7874 0.4064)
			(end -0.7874 -0.4064)
			(stroke
				(width 0.1524)
				(type default)
			)
			(layer "F.SilkS")
		)
		(fp_line
			(start -0.7874 -0.4064)
			(end 0.7874 -0.4064)
			(stroke
				(width 0.1524)
				(type default)
			)
			(layer "F.SilkS")
		)
		(fp_poly
			(pts
				(xy -0.508 0.2794) (xy -0.508 0.2286) (xy -0.635 0.2286) (xy -0.635 -0.254) (xy -0.5334 -0.254)
				(xy -0.5334 -0.2794) (xy 0.5334 -0.2794) (xy 0.5334 -0.254) (xy 0.635 -0.254) (xy 0.635 0.254) (xy 0.5334 0.254)
				(xy 0.5334 0.2794)
			)
			(stroke
				(width 0)
				(type default)
			)
			(fill no)
			(layer "F.CrtYd")
		)
		(pad "1" smd rect
			(at 0.40005 0 180)
			(size 0.4572 0.508)
			(layers "F.Cu" "F.Mask" "F.Paste")
			(net "GND")
		)
		(pad "2" smd rect
			(at -0.40005 0 180)
			(size 0.4572 0.508)
			(layers "F.Cu" "F.Mask" "F.Paste")
			(net "N49382752")
		)
	)
	(footprint ""
		(layer "F.Cu")
		(at 103.329994 -116.985796 180)
		(property "Reference" "PC126"
			(at 5.918454 -0.749808 0)
			(unlocked yes)
			(layer "F.SilkS")
			(effects
				(font
					(size 0.7874 0.5842)
					(thickness 0.1524)
				)
				(justify left)
			)
		)
		(property "Value" ""
			(at 0 0 180)
			(layer "F.Fab")
			(effects
				(font
					(size 1.27 1.27)
				)
			)
		)
		(duplicate_pad_numbers_are_jumpers no)
		(fp_line
			(start 1.905 0.8636)
			(end -1.905 0.8636)
			(stroke
				(width 0.1524)
				(type default)
			)
			(layer "F.SilkS")
		)
		(fp_line
			(start 1.905 -0.8636)
			(end 1.905 0.8636)
			(stroke
				(width 0.1524)
				(type default)
			)
			(layer "F.SilkS")
		)
		(fp_line
			(start 0 0.8382)
			(end 0 -0.8382)
			(stroke
				(width 0.1524)
				(type default)
			)
			(layer "F.SilkS")
		)
		(fp_line
			(start -1.905 0.8636)
			(end -1.905 -0.8636)
			(stroke
				(width 0.1524)
				(type default)
			)
			(layer "F.SilkS")
		)
		(fp_line
			(start -1.905 -0.8636)
			(end 1.905 -0.8636)
			(stroke
				(width 0.1524)
				(type default)
			)
			(layer "F.SilkS")
		)
		(fp_rect
			(start -1.524 0.7366)
			(end 1.524 -0.7366)
			(stroke
				(width 0)
				(type default)
			)
			(fill no)
			(layer "F.CrtYd")
		)
		(pad "1" smd rect
			(at 0.94996 0 180)
			(size 1.1176 1.3716)
			(layers "F.Cu" "F.Mask" "F.Paste")
			(net "GND")
		)
		(pad "2" smd rect
			(at -0.94996 0 180)
			(size 1.1176 1.3716)
			(layers "F.Cu" "F.Mask" "F.Paste")
			(net "PV_VCCP_NODE1")
		)
	)
	(footprint ""
		(layer "F.Cu")
		(at 12.26058 -154.13736 90)
		(property "Reference" "C549"
			(at -5.109464 8.025892 90)
			(unlocked yes)
			(layer "F.SilkS")
			(effects
				(font
					(size 0.7874 0.5842)
					(thickness 0.1524)
				)
				(justify left)
			)
		)
		(property "Value" ""
			(at 0 0 90)
			(layer "F.Fab")
			(effects
				(font
					(size 1.27 1.27)
				)
			)
		)
		(duplicate_pad_numbers_are_jumpers no)
		(fp_line
			(start 0.7874 -0.4064)
			(end 0.7874 0.4064)
			(stroke
				(width 0.1524)
				(type default)
			)
			(layer "F.SilkS")
		)
		(fp_line
			(start -0.7874 -0.4064)
			(end 0.7874 -0.4064)
			(stroke
				(width 0.1524)
				(type default)
			)
			(layer "F.SilkS")
		)
		(fp_line
			(start 0 0.381)
			(end 0 -0.381)
			(stroke
				(width 0.1524)
				(type default)
			)
			(layer "F.SilkS")
		)
		(fp_line
			(start 0.7874 0.4064)
			(end -0.7874 0.4064)
			(stroke
				(width 0.1524)
				(type default)
			)
			(layer "F.SilkS")
		)
		(fp_line
			(start -0.7874 0.4064)
			(end -0.7874 -0.4064)
			(stroke
				(width 0.1524)
				(type default)
			)
			(layer "F.SilkS")
		)
		(fp_poly
			(pts
				(xy -0.5334 0.254) (xy -0.635 0.254) (xy -0.635 0.2286) (xy -0.635 -0.254) (xy -0.5334 -0.254) (xy -0.5334 -0.2794)
				(xy 0.5334 -0.2794) (xy 0.5334 -0.254) (xy 0.635 -0.254) (xy 0.635 0.254) (xy 0.5334 0.254) (xy 0.5334 0.2794)
				(xy -0.508 0.2794) (xy -0.5334 0.2794)
			)
			(stroke
				(width 0)
				(type default)
			)
			(fill no)
			(layer "F.CrtYd")
		)
		(pad "1" smd rect
			(at 0.40005 0 90)
			(size 0.4572 0.508)
			(layers "F.Cu" "F.Mask" "F.Paste")
			(net "N54258513")
		)
		(pad "2" smd rect
			(at -0.40005 0 90)
			(size 0.4572 0.508)
			(layers "F.Cu" "F.Mask" "F.Paste")
			(net "N54258515")
		)
	)
)
